# S9S_MB_2U (Grand Teton) — schematic netlist excerpt (pin names and nets, part order shuffled) for the footprints in the layout excerpt that follows; sources: Cadence DE-HDL packaged netlist, KiCad conversion of 03242023_DA0F0TMBIJ0_F0T_Motherboard_J_brd_V01_OCP.brd

PU36  ISL99390FRZTR5935  ISL99390FRZ-TR5935 IC  pkg QFN21_6X5XB  page 279
  VOS  = PVCCD_HV_CPU0_VOS
  AGND  = GND
  VCC  = PVCCD_HV_CPU0_VDD1
  PVCC  = PVCCFA_EHV_CPU0_PVCC
  PGND1  = GND
  GL1  = NC
  PGND2  = GND
  SW  = SW_PVCCD_HV_CPU0_SW1
  VIN1  = SW_P12V_PVCCINFAON_CPU0_FLT
  VIN2  = SW_P12V_PVCCINFAON_CPU0_FLT
  DNC  = NC
  PHASE  = SW_PVCCD_HV_CPU0_BOOTR1
  BOOT  = SW_PVCCD_HV_CPU0_BOOT1
  PWM  = PVCCD_HV_CPU0_APWM1
  EN  = PVCCD_HV_CPU0_VDD1
  TOUT_FLT  = PVCCD_HV_CPU0_ATSEN
  LSET  = PVCCD_HV_CPU0_LSET1
  IOUT  = PVCCD_HV_CPU0_ACSP1
  REFIN  = PVCCD_HV_CPU0_VREF
  PGND3  = GND
  GL2  = NC

(kicad_pcb
	(version 20260206)
	(generator "pcbnew")
	(generator_version "10.0")
	(general
		(thickness 1.6)
		(legacy_teardrops no)
	)
	(paper "A4")
	(title_block
		(title "03242023_DA0F0TMBIJ0_F0T_Motherboard_J_brd_V01_OCP.brd")
		(comment 1 "Grand Teton / footprints 1843-1843 of 6105")
	)
	(layers
		(0 "F.Cu" signal "TOP")
		(4 "In1.Cu" signal "GND")
		(6 "In2.Cu" signal "IN1")
		(8 "In3.Cu" signal "GND1")
		(10 "In4.Cu" signal "IN2")
		(12 "In5.Cu" signal "GND2")
		(14 "In6.Cu" signal "IN3")
		(16 "In7.Cu" signal "GND3")
		(18 "In8.Cu" signal "VCC")
		(20 "In9.Cu" signal "VCC1")
		(22 "In10.Cu" signal "GND4")
		(24 "In11.Cu" signal "IN4")
		(26 "In12.Cu" signal "GND5")
		(28 "In13.Cu" signal "IN5")
		(30 "In14.Cu" signal "GND6")
		(32 "In15.Cu" signal "IN6")
		(34 "In16.Cu" signal "GND7")
		(2 "B.Cu" signal "BOTTOM")
		(9 "F.Adhes" user "F.Adhesive")
		(11 "B.Adhes" user "B.Adhesive")
		(13 "F.Paste" user "Package Geometry/Pastemask Top")
		(15 "B.Paste" user "Package Geometry/Pastemask Bottom")
		(5 "F.SilkS" user "Ref Des/Silkscreen Top")
		(7 "B.SilkS" user "Ref Des/Silkscreen Bottom")
		(1 "F.Mask" user "Board Geometry/Soldermask Top")
		(3 "B.Mask" user "Board Geometry/Soldermask Bottom")
		(17 "Dwgs.User" user "User.Drawings")
		(19 "Cmts.User" user "User.Comments")
		(21 "Eco1.User" user "User.Eco1")
		(23 "Eco2.User" user "User.Eco2")
		(25 "Edge.Cuts" user "Board Geometry/Outline")
		(27 "Margin" user)
		(31 "F.CrtYd" user "Package Geometry/Place Bound Top")
		(29 "B.CrtYd" user "Package Geometry/Place Bound Bottom")
		(35 "F.Fab" user "Ref Des/Assembly Top")
		(33 "B.Fab" user "Ref Des/Assembly Bottom")
	)
	(footprint ""
		(layer "F.Cu")
		(at 416.009582 -162.185858 -90)
		(property "Reference" "PU36"
			(at -1.68148 -6.204458 0)
			(unlocked yes)
			(layer "F.SilkS")
			(effects
				(font
					(size 0.7874 0.5842)
					(thickness 0.1524)
				)
				(justify left)
			)
		)
		(property "Value" ""
			(at 0 0 270)
			(layer "F.Fab")
			(effects
				(font
					(size 1.27 1.27)
				)
			)
		)
		(duplicate_pad_numbers_are_jumpers no)
		(fp_line
			(start -2.500122 2.999994)
			(end -2.500122 2.339594)
			(stroke
				(width 0.1524)
				(type default)
			)
			(layer "F.SilkS")
		)
		(fp_line
			(start -2.2987 2.999994)
			(end -2.500122 2.999994)
			(stroke
				(width 0.1524)
				(type default)
			)
			(layer "F.SilkS")
		)
		(fp_line
			(start 2.500122 2.999994)
			(end 2.2987 2.999994)
			(stroke
				(width 0.1524)
				(type default)
			)
			(layer "F.SilkS")
		)
		(fp_line
			(start 2.500122 2.339594)
			(end 2.500122 2.999994)
			(stroke
				(width 0.1524)
				(type default)
			)
			(layer "F.SilkS")
		)
		(fp_line
			(start -2.500122 0.6604)
			(end -2.500122 0.229108)
			(stroke
				(width 0.1524)
				(type default)
			)
			(layer "F.SilkS")
		)
		(fp_line
			(start -2.500122 -2.529078)
			(end -2.500122 -2.999994)
			(stroke
				(width 0.1524)
				(type default)
			)
			(layer "F.SilkS")
		)
		(fp_line
			(start -2.500122 -2.999994)
			(end -2.24409 -2.999994)
			(stroke
				(width 0.1524)
				(type default)
			)
			(layer "F.SilkS")
		)
		(fp_line
			(start 2.31394 -2.999994)
			(end 2.500122 -2.999994)
			(stroke
				(width 0.1524)
				(type default)
			)
			(layer "F.SilkS")
		)
		(fp_line
			(start 2.500122 -2.999994)
			(end 2.500122 -2.44348)
			(stroke
				(width 0.1524)
				(type default)
			)
			(layer "F.SilkS")
		)
		(fp_poly
			(pts
				(xy -4.253992 -2.254758) (xy -5.269992 -1.746758) (xy -5.269992 -2.762758)
			)
			(stroke
				(width 0)
				(type default)
			)
			(fill yes)
			(layer "F.SilkS")
		)
		(fp_line
			(start -2.500122 2.999994)
			(end -2.500122 -2.999994)
			(stroke
				(width 0.1)
				(type default)
			)
			(layer "F.Fab")
		)
		(fp_line
			(start 2.500122 2.999994)
			(end -2.500122 2.999994)
			(stroke
				(width 0.1)
				(type default)
			)
			(layer "F.Fab")
		)
		(fp_line
			(start -2.500122 -2.999994)
			(end 2.500122 -2.999994)
			(stroke
				(width 0.1)
				(type default)
			)
			(layer "F.Fab")
		)
		(fp_line
			(start 2.500122 -2.999994)
			(end 2.500122 2.999994)
			(stroke
				(width 0.1)
				(type default)
			)
			(layer "F.Fab")
		)
		(fp_poly
			(pts
				(xy -4.218432 -2.783078) (xy -4.218432 -1.767078) (xy -3.202432 -2.275078)
			)
			(stroke
				(width 0)
				(type default)
			)
			(fill yes)
			(layer "F.Fab")
		)
		(pad "1" smd rect
			(at -2.400046 -2.275078)
			(size 0.2286 0.6096)
			(layers "F.Cu" "F.Mask" "F.Paste")
			(net "PVCCD_HV_CPU0_VOS")
		)
		(pad "2" smd rect
			(at -2.400046 -1.82499)
			(size 0.2286 0.6096)
			(layers "F.Cu" "F.Mask" "F.Paste")
			(net "GND")
		)
		(pad "3" smd rect
			(at -2.400046 -1.374902)
			(size 0.2286 0.6096)
			(layers "F.Cu" "F.Mask" "F.Paste")
			(net "PVCCD_HV_CPU0_VDD1")
		)
		(pad "4" smd rect
			(at -2.400046 -0.925068)
			(size 0.2286 0.6096)
			(layers "F.Cu" "F.Mask" "F.Paste")
			(net "PVCCFA_EHV_CPU0_PVCC")
		)
		(pad "5" smd rect
			(at -2.400046 -0.47498)
			(size 0.2286 0.6096)
			(layers "F.Cu" "F.Mask" "F.Paste")
			(net "GND")
		)
		(pad "6" smd rect
			(at -2.400046 -0.024892)
			(size 0.2286 0.6096)
			(layers "F.Cu" "F.Mask" "F.Paste")
			(net "Net_1920")
		)
		(pad "7_9-20_24" smd circle
			(at 0 1.150112)
			(size 0 0)
			(layers "F.Cu" "F.Mask" "F.Paste")
			(net "GND")
		)
		(pad "10_19" smd rect
			(at 0 2.899918)
			(size 0.6096 4.318)
			(layers "F.Cu" "F.Mask" "F.Paste")
			(net "SW_PVCCD_HV_CPU0_SW1")
		)
		(pad "25_29" smd rect
			(at 1.549908 -1.279906 180)
			(size 2.0574 2.3114)
			(layers "F.Cu" "F.Mask" "F.Paste")
			(net "SW_P12V_PVCCINFAON_CPU0_FLT")
		)
		(pad "30" smd rect
			(at 2.05994 -2.899918 270)
			(size 0.2286 0.6096)
			(layers "F.Cu" "F.Mask" "F.Paste")
			(net "SW_P12V_PVCCINFAON_CPU0_FLT")
		)
		(pad "31" smd rect
			(at 1.610106 -2.899918 270)
			(size 0.2286 0.6096)
			(layers "F.Cu" "F.Mask" "F.Paste")
			(net "Net_1919")
		)
		(pad "32" smd rect
			(at 1.160018 -2.899918 270)
			(size 0.2286 0.6096)
			(layers "F.Cu" "F.Mask" "F.Paste")
			(net "SW_PVCCD_HV_CPU0_BOOTR1")
		)
		(pad "33" smd rect
			(at 0.70993 -2.899918 270)
			(size 0.2286 0.6096)
			(layers "F.Cu" "F.Mask" "F.Paste")
			(net "SW_PVCCD_HV_CPU0_BOOT1")
		)
		(pad "34" smd rect
			(at 0.260096 -2.899918 270)
			(size 0.2286 0.6096)
			(layers "F.Cu" "F.Mask" "F.Paste")
			(net "PVCCD_HV_CPU0_APWM1")
		)
		(pad "35" smd rect
			(at -0.189992 -2.899918 270)
			(size 0.2286 0.6096)
			(layers "F.Cu" "F.Mask" "F.Paste")
			(net "PVCCD_HV_CPU0_VDD1")
		)
		(pad "36" smd rect
			(at -0.64008 -2.899918 270)
			(size 0.2286 0.6096)
			(layers "F.Cu" "F.Mask" "F.Paste")
			(net "PVCCD_HV_CPU0_ATSEN")
		)
		(pad "37" smd rect
			(at -1.089914 -2.899918 270)
			(size 0.2286 0.6096)
			(layers "F.Cu" "F.Mask" "F.Paste")
			(net "PVCCD_HV_CPU0_LSET1")
		)
		(pad "38" smd rect
			(at -1.540002 -2.899918 270)
			(size 0.2286 0.6096)
			(layers "F.Cu" "F.Mask" "F.Paste")
			(net "PVCCD_HV_CPU0_ACSP1")
		)
		(pad "39" smd rect
			(at -1.99009 -2.899918 270)
			(size 0.2286 0.6096)
			(layers "F.Cu" "F.Mask" "F.Paste")
			(net "PVCCD_HV_CPU0_VREF")
		)
		(pad "40" smd rect
			(at -0.87503 -1.27508 270)
			(size 1.7526 1.9558)
			(layers "F.Cu" "F.Mask" "F.Paste")
			(net "GND")
		)
		(pad "41" smd rect
			(at -1.525016 0.249936 180)
			(size 0.3048 0.4572)
			(layers "F.Cu" "F.Mask" "F.Paste")
			(net "Net_1921")
		)
	)
)
